# S9S_MB_2U (Grand Teton) — schematic netlist excerpt (pin names and nets, part order shuffled) for the footprints in the layout excerpt that follows; sources: Cadence DE-HDL packaged netlist, KiCad conversion of 03242023_DA0F0TMBIJ0_F0T_Motherboard_J_brd_V01_OCP.brd

R751  Q_RES  150 1% CHIP  pkg 0402LF  page 132 : A = P1V05_PCH_AUX ; B = H_DBP_PRDY_N_PCH
PC101  Q_CAP  470PF 50V 10% X7R  pkg 0402  page 284 : A = PVCCFA_EHV_FIVRA_CPU1_BTSEN ; B = GND

(kicad_pcb
	(version 20260206)
	(generator "pcbnew")
	(generator_version "10.0")
	(general
		(thickness 1.6)
		(legacy_teardrops no)
	)
	(paper "A4")
	(title_block
		(title "03242023_DA0F0TMBIJ0_F0T_Motherboard_J_brd_V01_OCP.brd")
		(comment 1 "Grand Teton / footprints 841-842 of 6105")
	)
	(layers
		(0 "F.Cu" signal "TOP")
		(4 "In1.Cu" signal "GND")
		(6 "In2.Cu" signal "IN1")
		(8 "In3.Cu" signal "GND1")
		(10 "In4.Cu" signal "IN2")
		(12 "In5.Cu" signal "GND2")
		(14 "In6.Cu" signal "IN3")
		(16 "In7.Cu" signal "GND3")
		(18 "In8.Cu" signal "VCC")
		(20 "In9.Cu" signal "VCC1")
		(22 "In10.Cu" signal "GND4")
		(24 "In11.Cu" signal "IN4")
		(26 "In12.Cu" signal "GND5")
		(28 "In13.Cu" signal "IN5")
		(30 "In14.Cu" signal "GND6")
		(32 "In15.Cu" signal "IN6")
		(34 "In16.Cu" signal "GND7")
		(2 "B.Cu" signal "BOTTOM")
		(9 "F.Adhes" user "F.Adhesive")
		(11 "B.Adhes" user "B.Adhesive")
		(13 "F.Paste" user "Package Geometry/Pastemask Top")
		(15 "B.Paste" user "Package Geometry/Pastemask Bottom")
		(5 "F.SilkS" user "Ref Des/Silkscreen Top")
		(7 "B.SilkS" user "Ref Des/Silkscreen Bottom")
		(1 "F.Mask" user "Board Geometry/Soldermask Top")
		(3 "B.Mask" user "Board Geometry/Soldermask Bottom")
		(17 "Dwgs.User" user "User.Drawings")
		(19 "Cmts.User" user "User.Comments")
		(21 "Eco1.User" user "User.Eco1")
		(23 "Eco2.User" user "User.Eco2")
		(25 "Edge.Cuts" user "Board Geometry/Outline")
		(27 "Margin" user)
		(31 "F.CrtYd" user "Package Geometry/Place Bound Top")
		(29 "B.CrtYd" user "Package Geometry/Place Bound Bottom")
		(35 "F.Fab" user "Ref Des/Assembly Top")
		(33 "B.Fab" user "Ref Des/Assembly Bottom")
	)
	(footprint ""
		(layer "F.Cu")
		(at 114.706654 -358.93375)
		(property "Reference" "PC101"
			(at 0 0 0)
			(layer "F.SilkS")
			(hide yes)
			(effects
				(font
					(size 1.27 1.27)
				)
			)
		)
		(property "Value" ""
			(at 0 0 0)
			(layer "F.Fab")
			(effects
				(font
					(size 1.27 1.27)
				)
			)
		)
		(duplicate_pad_numbers_are_jumpers no)
		(fp_line
			(start -0.7874 -0.4064)
			(end 0.7874 -0.4064)
			(stroke
				(width 0.1524)
				(type default)
			)
			(layer "F.SilkS")
		)
		(fp_line
			(start -0.7874 0.4064)
			(end -0.7874 -0.4064)
			(stroke
				(width 0.1524)
				(type default)
			)
			(layer "F.SilkS")
		)
		(fp_line
			(start 0.7874 -0.4064)
			(end 0.7874 0.4064)
			(stroke
				(width 0.1524)
				(type default)
			)
			(layer "F.SilkS")
		)
		(fp_line
			(start 0.7874 0.4064)
			(end -0.7874 0.4064)
			(stroke
				(width 0.1524)
				(type default)
			)
			(layer "F.SilkS")
		)
		(fp_line
			(start -0.67945 -0.305054)
			(end -0.12065 -0.305054)
			(stroke
				(width 0.1)
				(type default)
			)
			(layer "F.Fab")
		)
		(fp_line
			(start -0.67945 0.3048)
			(end -0.67945 -0.305054)
			(stroke
				(width 0.1)
				(type default)
			)
			(layer "F.Fab")
		)
		(fp_line
			(start -0.12065 -0.305054)
			(end -0.12065 -0.2794)
			(stroke
				(width 0.1)
				(type default)
			)
			(layer "F.Fab")
		)
		(fp_line
			(start -0.12065 -0.2794)
			(end 0.12065 -0.2794)
			(stroke
				(width 0.1)
				(type default)
			)
			(layer "F.Fab")
		)
		(fp_line
			(start -0.12065 0.2794)
			(end -0.12065 0.3048)
			(stroke
				(width 0.1)
				(type default)
			)
			(layer "F.Fab")
		)
		(fp_line
			(start -0.12065 0.3048)
			(end -0.67945 0.3048)
			(stroke
				(width 0.1)
				(type default)
			)
			(layer "F.Fab")
		)
		(fp_line
			(start 0.120396 0.2794)
			(end -0.12065 0.2794)
			(stroke
				(width 0.1)
				(type default)
			)
			(layer "F.Fab")
		)
		(fp_line
			(start 0.120396 0.3048)
			(end 0.120396 0.2794)
			(stroke
				(width 0.1)
				(type default)
			)
			(layer "F.Fab")
		)
		(fp_line
			(start 0.12065 -0.3048)
			(end 0.67945 -0.3048)
			(stroke
				(width 0.1)
				(type default)
			)
			(layer "F.Fab")
		)
		(fp_line
			(start 0.12065 -0.2794)
			(end 0.12065 -0.3048)
			(stroke
				(width 0.1)
				(type default)
			)
			(layer "F.Fab")
		)
		(fp_line
			(start 0.67945 -0.3048)
			(end 0.67945 0.3048)
			(stroke
				(width 0.1)
				(type default)
			)
			(layer "F.Fab")
		)
		(fp_line
			(start 0.67945 0.3048)
			(end 0.120396 0.3048)
			(stroke
				(width 0.1)
				(type default)
			)
			(layer "F.Fab")
		)
		(pad "1" smd circle
			(at -0.40005 0)
			(size 0 0)
			(layers "F.Cu" "F.Mask" "F.Paste")
			(net "PVCCFA_EHV_FIVRA_CPU1_BTSEN")
		)
		(pad "2" smd circle
			(at 0.40005 0)
			(size 0 0)
			(layers "F.Cu" "F.Mask" "F.Paste")
			(net "GND")
		)
	)
	(footprint ""
		(layer "F.Cu")
		(at 377.46559 -64.866012 180)
		(property "Reference" "R751"
			(at 0 0 180)
			(layer "F.SilkS")
			(hide yes)
			(effects
				(font
					(size 1.27 1.27)
				)
			)
		)
		(property "Value" ""
			(at 0 0 180)
			(layer "F.Fab")
			(effects
				(font
					(size 1.27 1.27)
				)
			)
		)
		(duplicate_pad_numbers_are_jumpers no)
		(fp_line
			(start 0.7874 0.4064)
			(end -0.7874 0.4064)
			(stroke
				(width 0.1524)
				(type default)
			)
			(layer "F.SilkS")
		)
		(fp_line
			(start 0.7874 -0.4064)
			(end 0.7874 0.4064)
			(stroke
				(width 0.1524)
				(type default)
			)
			(layer "F.SilkS")
		)
		(fp_line
			(start -0.7874 0.4064)
			(end -0.7874 -0.4064)
			(stroke
				(width 0.1524)
				(type default)
			)
			(layer "F.SilkS")
		)
		(fp_line
			(start -0.7874 -0.4064)
			(end 0.7874 -0.4064)
			(stroke
				(width 0.1524)
				(type default)
			)
			(layer "F.SilkS")
		)
		(fp_line
			(start 0.67945 0.3048)
			(end 0.120396 0.3048)
			(stroke
				(width 0.1)
				(type default)
			)
			(layer "F.Fab")
		)
		(fp_line
			(start 0.67945 -0.3048)
			(end 0.67945 0.3048)
			(stroke
				(width 0.1)
				(type default)
			)
			(layer "F.Fab")
		)
		(fp_line
			(start 0.12065 -0.2794)
			(end 0.12065 -0.3048)
			(stroke
				(width 0.1)
				(type default)
			)
			(layer "F.Fab")
		)
		(fp_line
			(start 0.12065 -0.3048)
			(end 0.67945 -0.3048)
			(stroke
				(width 0.1)
				(type default)
			)
			(layer "F.Fab")
		)
		(fp_line
			(start 0.120396 0.3048)
			(end 0.120396 0.2794)
			(stroke
				(width 0.1)
				(type default)
			)
			(layer "F.Fab")
		)
		(fp_line
			(start 0.120396 0.2794)
			(end -0.12065 0.2794)
			(stroke
				(width 0.1)
				(type default)
			)
			(layer "F.Fab")
		)
		(fp_line
			(start -0.12065 0.3048)
			(end -0.67945 0.3048)
			(stroke
				(width 0.1)
				(type default)
			)
			(layer "F.Fab")
		)
		(fp_line
			(start -0.12065 0.2794)
			(end -0.12065 0.3048)
			(stroke
				(width 0.1)
				(type default)
			)
			(layer "F.Fab")
		)
		(fp_line
			(start -0.12065 -0.2794)
			(end 0.12065 -0.2794)
			(stroke
				(width 0.1)
				(type default)
			)
			(layer "F.Fab")
		)
		(fp_line
			(start -0.12065 -0.305054)
			(end -0.12065 -0.2794)
			(stroke
				(width 0.1)
				(type default)
			)
			(layer "F.Fab")
		)
		(fp_line
			(start -0.67945 0.3048)
			(end -0.67945 -0.305054)
			(stroke
				(width 0.1)
				(type default)
			)
			(layer "F.Fab")
		)
		(fp_line
			(start -0.67945 -0.305054)
			(end -0.12065 -0.305054)
			(stroke
				(width 0.1)
				(type default)
			)
			(layer "F.Fab")
		)
		(pad "1" smd circle
			(at -0.40005 0 180)
			(size 0 0)
			(layers "F.Cu" "F.Mask" "F.Paste")
			(net "P1V05_PCH_AUX")
		)
		(pad "2" smd circle
			(at 0.40005 0 180)
			(size 0 0)
			(layers "F.Cu" "F.Mask" "F.Paste")
			(net "H_DBP_PRDY_N_PCH")
		)
	)
)
